#ISCELL
  mstr_misc dns *
  *
#ISCELL
  pure_quanta quanta_title_block_c *
  *
#ISCELL
  standard offpage *
  page282_i1
#CELL
  pure_quanta q_res *
  page282_i10
#CELL
  pure_quanta q_res *
  page282_i11
#ISCELL
  logical_power universal_gnd *
  page282_i12
#CELL
  pure_quanta q_cap *
  page282_i13
#ISCELL
  standard offpage *
  page282_i14
#CELL
  pure_quanta q_res *
  page282_i15
#CELL
  pure_quanta q_short *
  page282_i16
#ISCELL
  logical_power universal_gnd *
  page282_i17
#CELL
  pure_quanta q_res *
  page282_i18
#ISCELL
  logical_power vcc15 *
  page282_i19
#ISCELL
  standard offpage *
  page282_i2
#CELL
  pure_quanta q_res *
  page282_i20
#CELL
  pure_quanta q_res *
  page282_i21
#CELL
  pure_quanta q_cap *
  page282_i22
#ISCELL
  logical_power universal_gnd *
  page282_i23
#CELL
  pure_quanta q_cap *
  page282_i24
#ISCELL
  logical_power vcc15 *
  page282_i25
#ISCELL
  standard offpage *
  page282_i26
#ISCELL
  standard offpage *
  page282_i27
#CELL
  pure_quanta q_cap *
  page282_i28
#CELL
  pure_quanta q_res *
  page282_i29
#ISCELL
  standard offpage *
  page282_i3
#ISCELL
  standard offpage *
  page282_i30
#ISCELL
  standard offpage *
  page282_i31
#ISCELL
  standard offpage *
  page282_i32
#CELL
  pure_quanta q_res *
  page282_i33
#ISCELL
  standard offpage *
  page282_i34
#ISCELL
  standard offpage *
  page282_i35
#CELL
  pure_quanta q_res *
  page282_i36
#ISCELL
  logical_power vcc15 *
  page282_i37
#CELL
  pure_quanta q_res *
  page282_i38
#CELL
  pure_quanta q_res *
  page282_i39
#ISCELL
  logical_power universal_gnd *
  page282_i4
#CELL
  pure_quanta q_res *
  page282_i40
#CELL
  pure_quanta q_res *
  page282_i41
#CELL
  pure_quanta q_res *
  page282_i42
#CELL
  pure_quanta q_res *
  page282_i43
#CELL
  pure_quanta q_res *
  page282_i44
#CELL
  pure_quanta q_cap *
  page282_i45
#CELL
  pure_quanta q_res *
  page282_i46
#ISCELL
  logical_power vcc15 *
  page282_i47
#CELL
  pure_quanta q_res *
  page282_i48
#ISCELL
  logical_power universal_gnd *
  page282_i49
#ISCELL
  standard offpage *
  page282_i5
#CELL
  pure_quanta q_cap *
  page282_i50
#CELL
  pure_quanta q_cap *
  page282_i51
#ISCELL
  logical_power universal_gnd *
  page282_i52
#CELL
  pure_quanta isl69260irazt *
  page282_i53
#ISCELL
  logical_power universal_gnd *
  page282_i54
#ISCELL
  logical_power universal_gnd *
  page282_i55
#ISCELL
  logical_power universal_gnd *
  page282_i56
#CELL
  pure_quanta q_cap *
  page282_i57
#CELL
  pure_quanta q_res *
  page282_i58
#CELL
  pure_quanta q_res *
  page282_i59
#ISCELL
  standard offpage *
  page282_i6
#CELL
  pure_quanta q_res *
  page282_i60
#CELL
  pure_quanta q_res *
  page282_i61
#CELL
  pure_quanta q_res *
  page282_i62
#CELL
  pure_quanta q_res *
  page282_i63
#CELL
  pure_quanta q_res *
  page282_i64
#CELL
  pure_quanta q_res *
  page282_i65
#CELL
  pure_quanta q_res *
  page282_i66
#ISCELL
  logical_power universal_gnd *
  page282_i67
#CELL
  pure_quanta q_cap *
  page282_i68
#CELL
  pure_quanta q_cap *
  page282_i69
#CELL
  pure_quanta q_res *
  page282_i70
#ISCELL
  standard offpage *
  page282_i71
#ISCELL
  standard offpage *
  page282_i72
#ISCELL
  logical_power universal_gnd *
  page282_i73
#CELL
  pure_quanta q_cap *
  page282_i74
#ISCELL
  logical_power universal_gnd *
  page282_i75
#ISCELL
  standard offpage *
  page282_i76
#CELL
  pure_quanta q_cap *
  page282_i77
#CELL
  pure_quanta q_res *
  page282_i78
#ISCELL
  logical_power vcc15 *
  page282_i79
#CELL
  pure_quanta q_res *
  page282_i8
#ISCELL
  logical_power universal_gnd *
  page282_i80
#CELL
  pure_quanta q_res *
  page282_i81
#ISCELL
  logical_power universal_gnd *
  page282_i82
#ISCELL
  standard offpage *
  page282_i83
#ISCELL
  logical_power universal_gnd *
  page282_i84
#CELL
  pure_quanta q_res *
  page282_i85
#ISCELL
  logical_power vcc15 *
  page282_i86
#ISCELL
  standard offpage *
  page282_i87
#ISCELL
  standard offpage *
  page282_i88
#ISCELL
  logical_power universal_gnd *
  page282_i89
#CELL
  pure_quanta q_res *
  page282_i9
#ISCELL
  logical_power universal_gnd *
  page282_i90
#ISCELL
  logical_power universal_gnd *
  page282_i91
#ISCELL
  logical_power universal_gnd *
  page282_i92
#ISCELL
  logical_power universal_gnd *
  page282_i93
#ISCELL
  logical_power universal_gnd *
  page282_i94
#CELL
  pure_quanta q_res *
  page282_i95
#CELL
  pure_quanta q_cap *
  page282_i96
